(kicad_pcb
	(version 20260206)
	(generator "pcbnew")
	(generator_version "10.0")
	(general
		(thickness 1.6)
		(legacy_teardrops no)
	)
	(paper "A4")
	(title_block
		(title "Bryce Canyon_F.DPB_16315-1-OCP.brd")
		(comment 1 "Bryce Canyon / footprints 1641-1646 of 2223")
	)
	(layers
		(0 "F.Cu" signal "TOP")
		(4 "In1.Cu" signal "L2GND")
		(6 "In2.Cu" signal "L3")
		(8 "In3.Cu" signal "L4GND")
		(10 "In4.Cu" signal "L5")
		(12 "In5.Cu" signal "L6VCC")
		(14 "In6.Cu" signal "L7VCC")
		(16 "In7.Cu" signal "L8")
		(18 "In8.Cu" signal "L9GND")
		(20 "In9.Cu" signal "L10")
		(22 "In10.Cu" signal "L11GND")
		(2 "B.Cu" signal "BOTTOM")
		(9 "F.Adhes" user "F.Adhesive")
		(11 "B.Adhes" user "B.Adhesive")
		(13 "F.Paste" user "Package Geometry/Pastemask Top")
		(15 "B.Paste" user "Package Geometry/Pastemask Bottom")
		(5 "F.SilkS" user "Ref Des/Silkscreen Top")
		(7 "B.SilkS" user "Ref Des/Silkscreen Bottom")
		(1 "F.Mask" user "Board Geometry/Soldermask Top")
		(3 "B.Mask" user "Board Geometry/Soldermask Bottom")
		(17 "Dwgs.User" user "User.Drawings")
		(19 "Cmts.User" user "User.Comments")
		(21 "Eco1.User" user "User.Eco1")
		(23 "Eco2.User" user "User.Eco2")
		(25 "Edge.Cuts" user "Board Geometry/Outline")
		(27 "Margin" user)
		(31 "F.CrtYd" user "Package Geometry/Place Bound Top")
		(29 "B.CrtYd" user "Package Geometry/Place Bound Bottom")
		(35 "F.Fab" user "Ref Des/Assembly Top")
		(33 "B.Fab" user "Ref Des/Assembly Bottom")
	)
	(footprint ""
		(layer "F.Cu")
		(at 397.99895 -52.872894 -90)
		(property "Reference" "Q191"
			(at 0 0 270)
			(layer "F.SilkS")
			(hide yes)
			(effects
				(font
					(size 1.27 1.27)
				)
			)
		)
		(property "Value" "AO4406AL-GP"
			(at -3.707384 -1.5367 270)
			(unlocked yes)
			(layer "F.Fab")
			(hide yes)
			(effects
				(font
					(size 1.016 1.016)
					(thickness 0.1524)
				)
			)
		)
		(property "Device Type" "SOIC8H69"
			(at -3.707384 -3.0607 270)
			(unlocked yes)
			(layer "F.Fab")
			(hide yes)
			(effects
				(font
					(size 1.016 1.016)
					(thickness 0.1524)
				)
			)
		)
		(duplicate_pad_numbers_are_jumpers no)
		(fp_line
			(start -2.6289 3.4417)
			(end -2.6289 1.4732)
			(stroke
				(width 0.381)
				(type default)
			)
			(layer "F.SilkS")
		)
		(fp_line
			(start -2.7432 1.4224)
			(end -2.6416 1.4224)
			(stroke
				(width 0.1524)
				(type default)
			)
			(layer "F.SilkS")
		)
		(fp_line
			(start -2.7432 1.4224)
			(end 2.1336 1.4224)
			(stroke
				(width 0.1524)
				(type default)
			)
			(layer "F.SilkS")
		)
		(fp_line
			(start 2.1336 1.4224)
			(end 2.1336 -1.4224)
			(stroke
				(width 0.1524)
				(type default)
			)
			(layer "F.SilkS")
		)
		(fp_line
			(start -2.1844 -0.0508)
			(end -2.7178 0.508)
			(stroke
				(width 0.1524)
				(type default)
			)
			(layer "F.SilkS")
		)
		(fp_line
			(start -2.7178 -0.508)
			(end -2.1844 -0.0508)
			(stroke
				(width 0.1524)
				(type default)
			)
			(layer "F.SilkS")
		)
		(fp_line
			(start -2.7432 -1.4224)
			(end -2.7432 1.4224)
			(stroke
				(width 0.1524)
				(type default)
			)
			(layer "F.SilkS")
		)
		(fp_line
			(start 2.1336 -1.4224)
			(end -2.7432 -1.4224)
			(stroke
				(width 0.1524)
				(type default)
			)
			(layer "F.SilkS")
		)
		(fp_poly
			(pts
				(xy -2.2098 -1.4224) (xy -2.2098 1.4224) (xy 2.2098 1.4224) (xy 2.2098 -1.4224)
			)
			(stroke
				(width 0)
				(type default)
			)
			(fill yes)
			(layer "F.SilkS")
		)
		(fp_rect
			(start -2.450084 2.999994)
			(end 2.450084 -2.999994)
			(stroke
				(width 0)
				(type default)
			)
			(fill no)
			(layer "F.CrtYd")
		)
		(fp_poly
			(pts
				(xy -2.8194 3.6322) (xy -2.8194 -3.6322) (xy 2.8194 -3.6322) (xy 2.8194 1.18364) (xy 2.450084 1.18364)
				(xy 2.450084 -2.999994) (xy -2.450084 -2.999994) (xy -2.450084 2.999994) (xy 2.450084 2.999994)
				(xy 2.450084 1.18618) (xy 2.8194 1.18618) (xy 2.8194 3.6322)
			)
			(stroke
				(width 0)
				(type default)
			)
			(fill no)
			(layer "F.CrtYd")
		)
		(fp_rect
			(start -2.8194 3.6322)
			(end 2.8194 -3.6322)
			(stroke
				(width 0)
				(type default)
			)
			(fill no)
			(layer "F.Fab")
		)
		(pad "1" smd rect
			(at -1.905 2.54 270)
			(size 0.635 1.651)
			(layers "F.Cu" "F.Mask" "F.Paste")
			(net "P5V_HDD32")
		)
		(pad "2" smd rect
			(at -0.635 2.54 270)
			(size 0.635 1.651)
			(layers "F.Cu" "F.Mask" "F.Paste")
			(net "P5V_HDD32")
		)
		(pad "3" smd rect
			(at 0.635 2.54 270)
			(size 0.635 1.651)
			(layers "F.Cu" "F.Mask" "F.Paste")
			(net "P5V_HDD32")
		)
		(pad "4" smd rect
			(at 1.905 2.54 270)
			(size 0.635 1.651)
			(layers "F.Cu" "F.Mask" "F.Paste")
			(net "SW_HDD_P32")
		)
		(pad "5" smd rect
			(at 1.905 -2.54 270)
			(size 0.635 1.651)
			(layers "F.Cu" "F.Mask" "F.Paste")
			(net "P5V_A_4")
		)
		(pad "6" smd rect
			(at 0.635 -2.54 270)
			(size 0.635 1.651)
			(layers "F.Cu" "F.Mask" "F.Paste")
			(net "P5V_A_4")
		)
		(pad "7" smd rect
			(at -0.635 -2.54 270)
			(size 0.635 1.651)
			(layers "F.Cu" "F.Mask" "F.Paste")
			(net "P5V_A_4")
		)
		(pad "8" smd rect
			(at -1.905 -2.54 270)
			(size 0.635 1.651)
			(layers "F.Cu" "F.Mask" "F.Paste")
			(net "P5V_A_4")
		)
	)
	(footprint ""
		(layer "F.Cu")
		(at 74.747628 -130.269996 -90)
		(property "Reference" "R508"
			(at 0 0 270)
			(layer "F.SilkS")
			(hide yes)
			(effects
				(font
					(size 1.27 1.27)
				)
			)
		)
		(property "Value" "4K7R2J-2-GP"
			(at 0.064008 -3.993896 270)
			(unlocked yes)
			(layer "F.Fab")
			(hide yes)
			(effects
				(font
					(size 1.016 1.016)
					(thickness 0.1524)
				)
			)
		)
		(property "Device Type" "R402H16"
			(at 0.064008 -5.517896 270)
			(unlocked yes)
			(layer "F.Fab")
			(hide yes)
			(effects
				(font
					(size 1.016 1.016)
					(thickness 0.1524)
				)
			)
		)
		(duplicate_pad_numbers_are_jumpers no)
		(fp_line
			(start -0.508 -0.9398)
			(end -0.508 0.9398)
			(stroke
				(width 0.1524)
				(type default)
			)
			(layer "F.SilkS")
		)
		(fp_line
			(start 0.508 -0.9398)
			(end -0.508 -0.9398)
			(stroke
				(width 0.1524)
				(type default)
			)
			(layer "F.SilkS")
		)
		(fp_rect
			(start -0.508 0.9398)
			(end 0.508 -0.9398)
			(stroke
				(width 0)
				(type default)
			)
			(fill no)
			(layer "F.CrtYd")
		)
		(fp_rect
			(start -0.508 0.9398)
			(end 0.508 -0.9398)
			(stroke
				(width 0)
				(type default)
			)
			(fill no)
			(layer "F.Fab")
		)
		(pad "1" smd custom
			(at 0 -0.4445 270)
			(size 0.1397 0.1397)
			(layers "F.Cu" "F.Mask" "F.Paste")
			(net "DRIVE_A_14_ACT")
			(options
				(clearance outline)
				(anchor circle)
			)
			(primitives
				(gr_poly
					(pts
						(arc
							(start -0.1778 -0.2794)
							(mid -0.249642 -0.249642)
							(end -0.2794 -0.1778)
						)
						(arc
							(start -0.2794 0.1778)
							(mid -0.249642 0.249642)
							(end -0.1778 0.2794)
						)
						(arc
							(start 0.1778 0.2794)
							(mid 0.249642 0.249642)
							(end 0.2794 0.1778)
						)
						(arc
							(start 0.2794 -0.1778)
							(mid 0.249642 -0.249642)
							(end 0.1778 -0.2794)
						)
					)
					(width 0)
					(fill yes)
				)
			)
		)
		(pad "2" smd custom
			(at 0 0.4445 270)
			(size 0.1397 0.1397)
			(layers "F.Cu" "F.Mask" "F.Paste")
			(net "GND")
			(options
				(clearance outline)
				(anchor circle)
			)
			(primitives
				(gr_poly
					(pts
						(arc
							(start -0.1778 -0.2794)
							(mid -0.249642 -0.249642)
							(end -0.2794 -0.1778)
						)
						(arc
							(start -0.2794 0.1778)
							(mid -0.249642 0.249642)
							(end -0.1778 0.2794)
						)
						(arc
							(start 0.1778 0.2794)
							(mid 0.249642 0.249642)
							(end 0.2794 0.1778)
						)
						(arc
							(start 0.2794 -0.1778)
							(mid 0.249642 -0.249642)
							(end 0.1778 -0.2794)
						)
					)
					(width 0)
					(fill yes)
				)
			)
		)
	)
	(footprint ""
		(layer "F.Cu")
		(at 54.546246 -157.204918 -90)
		(property "Reference" "R439"
			(at 0 0 270)
			(layer "F.SilkS")
			(hide yes)
			(effects
				(font
					(size 1.27 1.27)
				)
			)
		)
		(property "Value" "0R2J-2-GP"
			(at 0.064008 -3.993896 270)
			(unlocked yes)
			(layer "F.Fab")
			(hide yes)
			(effects
				(font
					(size 1.016 1.016)
					(thickness 0.1524)
				)
			)
		)
		(property "Device Type" "R402H16"
			(at 0.064008 -5.517896 270)
			(unlocked yes)
			(layer "F.Fab")
			(hide yes)
			(effects
				(font
					(size 1.016 1.016)
					(thickness 0.1524)
				)
			)
		)
		(duplicate_pad_numbers_are_jumpers no)
		(fp_line
			(start -0.508 -0.9398)
			(end -0.508 0.9398)
			(stroke
				(width 0.1524)
				(type default)
			)
			(layer "F.SilkS")
		)
		(fp_line
			(start 0.508 -0.9398)
			(end -0.508 -0.9398)
			(stroke
				(width 0.1524)
				(type default)
			)
			(layer "F.SilkS")
		)
		(fp_rect
			(start -0.508 0.9398)
			(end 0.508 -0.9398)
			(stroke
				(width 0)
				(type default)
			)
			(fill no)
			(layer "F.CrtYd")
		)
		(fp_rect
			(start -0.508 0.9398)
			(end 0.508 -0.9398)
			(stroke
				(width 0)
				(type default)
			)
			(fill no)
			(layer "F.Fab")
		)
		(pad "1" smd custom
			(at 0 -0.4445 270)
			(size 0.1397 0.1397)
			(layers "F.Cu" "F.Mask" "F.Paste")
			(net "DRIVE_A_13_PWR")
			(options
				(clearance outline)
				(anchor circle)
			)
			(primitives
				(gr_poly
					(pts
						(arc
							(start -0.1778 -0.2794)
							(mid -0.249642 -0.249642)
							(end -0.2794 -0.1778)
						)
						(arc
							(start -0.2794 0.1778)
							(mid -0.249642 0.249642)
							(end -0.1778 0.2794)
						)
						(arc
							(start 0.1778 0.2794)
							(mid 0.249642 0.249642)
							(end 0.2794 0.1778)
						)
						(arc
							(start 0.2794 -0.1778)
							(mid 0.249642 -0.249642)
							(end 0.1778 -0.2794)
						)
					)
					(width 0)
					(fill yes)
				)
			)
		)
		(pad "2" smd custom
			(at 0 0.4445 270)
			(size 0.1397 0.1397)
			(layers "F.Cu" "F.Mask" "F.Paste")
			(net "SW_PWR_R_HDD13")
			(options
				(clearance outline)
				(anchor circle)
			)
			(primitives
				(gr_poly
					(pts
						(arc
							(start -0.1778 -0.2794)
							(mid -0.249642 -0.249642)
							(end -0.2794 -0.1778)
						)
						(arc
							(start -0.2794 0.1778)
							(mid -0.249642 0.249642)
							(end -0.1778 0.2794)
						)
						(arc
							(start 0.1778 0.2794)
							(mid 0.249642 0.249642)
							(end 0.2794 0.1778)
						)
						(arc
							(start 0.2794 -0.1778)
							(mid 0.249642 -0.249642)
							(end 0.1778 -0.2794)
						)
					)
					(width 0)
					(fill yes)
				)
			)
		)
	)
	(footprint ""
		(layer "F.Cu")
		(at 150.440898 -304.462942 180)
		(property "Reference" "C99"
			(at 0 0 180)
			(layer "F.SilkS")
			(hide yes)
			(effects
				(font
					(size 1.27 1.27)
				)
			)
		)
		(property "Value" "SC1U25V3KX-GP"
			(at 0 -2.8194 180)
			(unlocked yes)
			(layer "F.Fab")
			(hide yes)
			(effects
				(font
					(size 1.016 1.016)
					(thickness 0.1524)
				)
			)
		)
		(property "Device Type" "C603H36"
			(at 0 -4.3434 180)
			(unlocked yes)
			(layer "F.Fab")
			(hide yes)
			(effects
				(font
					(size 1.016 1.016)
					(thickness 0.1524)
				)
			)
		)
		(duplicate_pad_numbers_are_jumpers no)
		(fp_line
			(start 0.508 0)
			(end -0.508 0)
			(stroke
				(width 0.2032)
				(type default)
			)
			(layer "F.SilkS")
		)
		(fp_rect
			(start -0.5842 1.3335)
			(end 0.5842 -1.3335)
			(stroke
				(width 0)
				(type default)
			)
			(fill no)
			(layer "F.CrtYd")
		)
		(fp_rect
			(start -0.5842 1.3335)
			(end 0.5842 -1.3335)
			(stroke
				(width 0)
				(type default)
			)
			(fill no)
			(layer "F.Fab")
		)
		(pad "1" smd custom
			(at 0 -0.762 180)
			(size 0.2159 0.2159)
			(layers "F.Cu" "F.Mask" "F.Paste")
			(net "P12V_HDD4")
			(options
				(clearance outline)
				(anchor circle)
			)
			(primitives
				(gr_poly
					(pts
						(arc
							(start -0.3302 -0.4318)
							(mid -0.402042 -0.402042)
							(end -0.4318 -0.3302)
						)
						(arc
							(start -0.4318 0.3302)
							(mid -0.402042 0.402042)
							(end -0.3302 0.4318)
						)
						(arc
							(start 0.3302 0.4318)
							(mid 0.402042 0.402042)
							(end 0.4318 0.3302)
						)
						(arc
							(start 0.4318 -0.3302)
							(mid 0.402042 -0.402042)
							(end 0.3302 -0.4318)
						)
					)
					(width 0)
					(fill yes)
				)
			)
		)
		(pad "2" smd custom
			(at 0 0.762 180)
			(size 0.2159 0.2159)
			(layers "F.Cu" "F.Mask" "F.Paste")
			(net "GND")
			(options
				(clearance outline)
				(anchor circle)
			)
			(primitives
				(gr_poly
					(pts
						(arc
							(start -0.3302 -0.4318)
							(mid -0.402042 -0.402042)
							(end -0.4318 -0.3302)
						)
						(arc
							(start -0.4318 0.3302)
							(mid -0.402042 0.402042)
							(end -0.3302 0.4318)
						)
						(arc
							(start 0.3302 0.4318)
							(mid 0.402042 0.402042)
							(end 0.4318 0.3302)
						)
						(arc
							(start 0.4318 -0.3302)
							(mid 0.402042 -0.402042)
							(end 0.3302 -0.4318)
						)
					)
					(width 0)
					(fill yes)
				)
			)
		)
	)
	(footprint ""
		(layer "F.Cu")
		(at 281.269948 17.480534)
		(property "Reference" "U44"
			(at 0 0 0)
			(layer "F.SilkS")
			(hide yes)
			(effects
				(font
					(size 1.27 1.27)
				)
			)
		)
		(property "Value" "74LVC2G07GW-GP"
			(at -2.3622 -8.2042 0)
			(unlocked yes)
			(layer "F.Fab")
			(hide yes)
			(effects
				(font
					(size 1.016 1.016)
					(thickness 0.1524)
				)
			)
		)
		(property "Device Type" "SOT-363H44"
			(at -2.3622 -10.1092 0)
			(unlocked yes)
			(layer "F.Fab")
			(hide yes)
			(effects
				(font
					(size 1.016 1.016)
					(thickness 0.1524)
				)
			)
		)
		(duplicate_pad_numbers_are_jumpers no)
		(fp_line
			(start -1.4478 -1.7018)
			(end -1.4478 1.7018)
			(stroke
				(width 0.1524)
				(type default)
			)
			(layer "F.SilkS")
		)
		(fp_line
			(start -1.4478 1.7018)
			(end 1.4478 1.7018)
			(stroke
				(width 0.1524)
				(type default)
			)
			(layer "F.SilkS")
		)
		(fp_line
			(start -1.27 1.524)
			(end -1.27 0.6604)
			(stroke
				(width 0.4826)
				(type default)
			)
			(layer "F.SilkS")
		)
		(fp_line
			(start 1.4478 -1.7018)
			(end -1.4478 -1.7018)
			(stroke
				(width 0.1524)
				(type default)
			)
			(layer "F.SilkS")
		)
		(fp_line
			(start 1.4478 1.7018)
			(end 1.4478 -1.7018)
			(stroke
				(width 0.1524)
				(type default)
			)
			(layer "F.SilkS")
		)
		(fp_poly
			(pts
				(xy -1.524 -1.778) (xy 1.524 -1.778) (xy 1.524 1.778) (xy -1.524 1.778)
			)
			(stroke
				(width 0)
				(type default)
			)
			(fill no)
			(layer "F.CrtYd")
		)
		(fp_poly
			(pts
				(xy -1.524 -1.778) (xy 1.524 -1.778) (xy 1.524 1.778) (xy -1.524 1.778)
			)
			(stroke
				(width 0)
				(type default)
			)
			(fill no)
			(layer "F.Fab")
		)
		(pad "1" smd rect
			(at -0.65024 0.9398)
			(size 0.4064 1.016)
			(layers "F.Cu" "F.Mask" "F.Paste")
			(net "DPB_PWR_BTN_A")
		)
		(pad "2" smd rect
			(at 0 0.9398)
			(size 0.4064 1.016)
			(layers "F.Cu" "F.Mask" "F.Paste")
			(net "GND")
		)
		(pad "3" smd rect
			(at 0.65024 0.9398)
			(size 0.4064 1.016)
			(layers "F.Cu" "F.Mask" "F.Paste")
			(net "DPB_PWR_BTN_B")
		)
		(pad "4" smd rect
			(at 0.65024 -0.9398)
			(size 0.4064 1.016)
			(layers "F.Cu" "F.Mask" "F.Paste")
			(net "DPB_PWR_BTN_BUF_B")
		)
		(pad "5" smd rect
			(at 0 -0.9398)
			(size 0.4064 1.016)
			(layers "F.Cu" "F.Mask" "F.Paste")
			(net "P3V3_BIAS")
		)
		(pad "6" smd rect
			(at -0.65024 -0.9398)
			(size 0.4064 1.016)
			(layers "F.Cu" "F.Mask" "F.Paste")
			(net "DPB_PWR_BTN_BUF_A")
		)
	)
	(footprint ""
		(layer "F.Cu")
		(at 224.522538 -377.00458 180)
		(property "Reference" "R172"
			(at 0 0 180)
			(layer "F.SilkS")
			(hide yes)
			(effects
				(font
					(size 1.27 1.27)
				)
			)
		)
		(property "Value" "0R2J-2-GP"
			(at 0.064008 -3.993896 180)
			(unlocked yes)
			(layer "F.Fab")
			(hide yes)
			(effects
				(font
					(size 1.016 1.016)
					(thickness 0.1524)
				)
			)
		)
		(property "Device Type" "R402H16"
			(at 0.064008 -5.517896 180)
			(unlocked yes)
			(layer "F.Fab")
			(hide yes)
			(effects
				(font
					(size 1.016 1.016)
					(thickness 0.1524)
				)
			)
		)
		(duplicate_pad_numbers_are_jumpers no)
		(fp_line
			(start 0.508 -0.9398)
			(end -0.508 -0.9398)
			(stroke
				(width 0.1524)
				(type default)
			)
			(layer "F.SilkS")
		)
		(fp_line
			(start -0.508 -0.9398)
			(end -0.508 0.9398)
			(stroke
				(width 0.1524)
				(type default)
			)
			(layer "F.SilkS")
		)
		(fp_rect
			(start -0.508 0.9398)
			(end 0.508 -0.9398)
			(stroke
				(width 0)
				(type default)
			)
			(fill no)
			(layer "F.CrtYd")
		)
		(fp_rect
			(start -0.508 0.9398)
			(end 0.508 -0.9398)
			(stroke
				(width 0)
				(type default)
			)
			(fill no)
			(layer "F.Fab")
		)
		(pad "1" smd custom
			(at 0 -0.4445 180)
			(size 0.1397 0.1397)
			(layers "F.Cu" "F.Mask" "F.Paste")
			(net "IO_EXP3_LED_SCL")
			(options
				(clearance outline)
				(anchor circle)
			)
			(primitives
				(gr_poly
					(pts
						(arc
							(start -0.1778 -0.2794)
							(mid -0.249642 -0.249642)
							(end -0.2794 -0.1778)
						)
						(arc
							(start -0.2794 0.1778)
							(mid -0.249642 0.249642)
							(end -0.1778 0.2794)
						)
						(arc
							(start 0.1778 0.2794)
							(mid 0.249642 0.249642)
							(end 0.2794 0.1778)
						)
						(arc
							(start 0.2794 -0.1778)
							(mid 0.249642 -0.249642)
							(end 0.1778 -0.2794)
						)
					)
					(width 0)
					(fill yes)
				)
			)
		)
		(pad "2" smd custom
			(at 0 0.4445 180)
			(size 0.1397 0.1397)
			(layers "F.Cu" "F.Mask" "F.Paste")
			(net "I2C_DRIVE_B_FLT_LED_SCL")
			(options
				(clearance outline)
				(anchor circle)
			)
			(primitives
				(gr_poly
					(pts
						(arc
							(start -0.1778 -0.2794)
							(mid -0.249642 -0.249642)
							(end -0.2794 -0.1778)
						)
						(arc
							(start -0.2794 0.1778)
							(mid -0.249642 0.249642)
							(end -0.1778 0.2794)
						)
						(arc
							(start 0.1778 0.2794)
							(mid 0.249642 0.249642)
							(end 0.2794 0.1778)
						)
						(arc
							(start 0.2794 -0.1778)
							(mid 0.249642 -0.249642)
							(end 0.1778 -0.2794)
						)
					)
					(width 0)
					(fill yes)
				)
			)
		)
	)
)
